FILE_TYPE = CONNECTIVITY;
{Allegro Design Entry HDL 16.6-p007 (v16-6-112F) 10/10/2012}
"PAGE_NUMBER" = 262;
0"NC";
END.
